#ISCELL
  mstr_symbols intel_corp_bpage *
  *
#ISCELL
  w_power w_vcc_circle *
  page148_i10
#ISCELL
  mstr_standard offpage *
  page148_i12
#ISCELL
  mstr_standard offpage *
  page148_i13
#ISCELL
  w_power w_vcc_circle *
  page148_i14
#ISCELL
  w_power w_vcc_circle *
  page148_i15
#CELL
  mstr_discrete res *
  page148_i16
#ISCELL
  w_power w_vcc_circle *
  page148_i17
#ISCELL
  mstr_symbols p3v3_stby *
  page148_i18
#ISCELL
  w_power w_vcc_circle *
  page148_i19
#ISCELL
  mstr_symbols p3v3_stby *
  page148_i2
#CELL
  dev_discrete cap_a *
  page148_i20
#ISCELL
  mstr_symbols pvccio_cpu0 *
  page148_i21
#ISCELL
  mstr_symbols gnd *
  page148_i22
#CELL
  mstr_discrete res *
  page148_i23
#ISCELL
  mstr_standard offpage *
  page148_i25
#ISCELL
  w_power w_vcc_circle *
  page148_i26
#ISCELL
  w_power w_vcc_circle *
  page148_i27
#CELL
  w_hdl ast2520a1-gp-gp *
  page148_i28
#ISCELL
  mstr_symbols gnd *
  page148_i3
#ISCELL
  mstr_symbols p3v3_stby *
  page148_i4
#ISCELL
  w_power w_vcc_circle *
  page148_i6
#ISCELL
  w_power w_vcc_circle *
  page148_i7
#ISCELL
  w_power w_vcc_circle *
  page148_i8
#ISCELL
  w_power w_vcc_circle *
  page148_i9
